# T6G (Grand Teton) — schematic netlist excerpt (pin names and nets, part order shuffled) for the footprints in the layout excerpt that follows; sources: Cadence DE-HDL packaged netlist, KiCad conversion of 04192023_DAF0TMB3IC0_F0TG_MB_C_brd_V02_OCP.brd

U50  MAX11617EEET  MAX11617EEE+T EMPTY  pkg QSOP16_0-635_4-9X3-89  page 258
  \ain11||ref\  = MAX11617_2_VREF_R
  AIN10  = GND
  AIN9  = GND
  AIN8  = GND
  AIN0  = P5V_AUX_ADC_MAM
  AIN1  = P1V8_AUX_ADC_MAM
  AIN2  = P1V2_AUX_ADC_MAM
  AIN3  = P1V8_CPU0_RT_1D_ADC_MAM
  AIN4  = P1V8_CPU1_RT_1D_ADC_MAM
  AIN5  = PVDD_33_S5_ADC_MAM
  AIN6  = PVDD18_S5_P0_ADC_MAM
  AIN7  = PVDD18_S5_P1_ADC_MAM
  SCL  = SMB_SEN_MAM_2_3V3AUX_SCL
  SDA  = SMB_SEN_MAM_2_3V3AUX_SDA
  GND  = GND
  VDD  = P3V3_MAX11617_2_VDD

C6092  Q_CAP  1UF 25V 10% X6S  pkg C0402  page 179 : A = P3V3_AUX_CPU0_USB2_AVDD33 ; B = GND

(kicad_pcb
	(version 20260206)
	(generator "pcbnew")
	(generator_version "10.0")
	(general
		(thickness 1.6)
		(legacy_teardrops no)
	)
	(paper "A4")
	(title_block
		(title "04192023_DAF0TMB3IC0_F0TG_MB_C_brd_V02_OCP.brd")
		(comment 1 "Grand Teton / footprints 6833-6834 of 8354")
	)
	(layers
		(0 "F.Cu" signal "TOP")
		(4 "In1.Cu" signal "GND")
		(6 "In2.Cu" signal "IN1")
		(8 "In3.Cu" signal "GND1")
		(10 "In4.Cu" signal "IN2")
		(12 "In5.Cu" signal "GND2")
		(14 "In6.Cu" signal "IN3")
		(16 "In7.Cu" signal "GND3")
		(18 "In8.Cu" signal "VCC")
		(20 "In9.Cu" signal "VCC1")
		(22 "In10.Cu" signal "GND4")
		(24 "In11.Cu" signal "IN4")
		(26 "In12.Cu" signal "GND5")
		(28 "In13.Cu" signal "IN5")
		(30 "In14.Cu" signal "GND6")
		(32 "In15.Cu" signal "IN6")
		(34 "In16.Cu" signal "GND7")
		(2 "B.Cu" signal "BOTTOM")
		(9 "F.Adhes" user "F.Adhesive")
		(11 "B.Adhes" user "B.Adhesive")
		(13 "F.Paste" user "Package Geometry/Pastemask Top")
		(15 "B.Paste" user "Package Geometry/Pastemask Bottom")
		(5 "F.SilkS" user "Ref Des/Silkscreen Top")
		(7 "B.SilkS" user "Ref Des/Silkscreen Bottom")
		(1 "F.Mask" user "Board Geometry/Soldermask Top")
		(3 "B.Mask" user "Board Geometry/Soldermask Bottom")
		(17 "Dwgs.User" user "User.Drawings")
		(19 "Cmts.User" user "User.Comments")
		(21 "Eco1.User" user "User.Eco1")
		(23 "Eco2.User" user "User.Eco2")
		(25 "Edge.Cuts" user "Board Geometry/Outline")
		(27 "Margin" user)
		(31 "F.CrtYd" user "Package Geometry/Place Bound Top")
		(29 "B.CrtYd" user "Package Geometry/Place Bound Bottom")
		(35 "F.Fab" user "Ref Des/Assembly Top")
		(33 "B.Fab" user "Ref Des/Assembly Bottom")
	)
	(footprint ""
		(layer "B.Cu")
		(at 249.904504 -325.613522)
		(property "Reference" "U50"
			(at 1.648968 -3.641852 0)
			(unlocked yes)
			(layer "B.SilkS")
			(effects
				(font
					(size 0.7874 0.5842)
					(thickness 0.1524)
				)
				(justify left mirror)
			)
		)
		(property "Value" ""
			(at 0 0 0)
			(layer "B.Fab")
			(effects
				(font
					(size 1.27 1.27)
				)
				(justify mirror)
			)
		)
		(duplicate_pad_numbers_are_jumpers no)
		(fp_line
			(start -1.715516 -2.489962)
			(end -1.092962 -2.489962)
			(stroke
				(width 0.1524)
				(type default)
			)
			(layer "B.SilkS")
		)
		(fp_line
			(start -1.715516 2.489962)
			(end -1.715516 -2.489962)
			(stroke
				(width 0.1524)
				(type default)
			)
			(layer "B.SilkS")
		)
		(fp_line
			(start -1.092962 -2.489962)
			(end 0 -1.397)
			(stroke
				(width 0.1524)
				(type default)
			)
			(layer "B.SilkS")
		)
		(fp_line
			(start 0 -1.397)
			(end 1.092962 -2.489962)
			(stroke
				(width 0.1524)
				(type default)
			)
			(layer "B.SilkS")
		)
		(fp_line
			(start 1.092962 -2.489962)
			(end 1.715516 -2.489962)
			(stroke
				(width 0.1524)
				(type default)
			)
			(layer "B.SilkS")
		)
		(fp_line
			(start 1.715516 -2.489962)
			(end 1.715516 2.489962)
			(stroke
				(width 0.1524)
				(type default)
			)
			(layer "B.SilkS")
		)
		(fp_line
			(start 1.715516 2.489962)
			(end -1.715516 2.489962)
			(stroke
				(width 0.1524)
				(type default)
			)
			(layer "B.SilkS")
		)
		(fp_poly
			(pts
				(xy 5.225796 -2.72161) (xy 5.225796 -1.70561) (xy 4.209796 -2.21361)
			)
			(stroke
				(width 0)
				(type default)
			)
			(fill yes)
			(layer "B.SilkS")
		)
		(fp_line
			(start -1.994916 -2.489962)
			(end 1.994916 -2.489962)
			(stroke
				(width 0.1)
				(type default)
			)
			(layer "B.Fab")
		)
		(fp_line
			(start -1.994916 2.489962)
			(end -1.994916 -2.489962)
			(stroke
				(width 0.1)
				(type default)
			)
			(layer "B.Fab")
		)
		(fp_line
			(start 1.994916 -2.489962)
			(end 1.994916 2.489962)
			(stroke
				(width 0.1)
				(type default)
			)
			(layer "B.Fab")
		)
		(fp_line
			(start 1.994916 2.489962)
			(end -1.994916 2.489962)
			(stroke
				(width 0.1)
				(type default)
			)
			(layer "B.Fab")
		)
		(fp_poly
			(pts
				(xy 4.699 -2.7305) (xy 4.699 -1.7145) (xy 3.683 -2.2225)
			)
			(stroke
				(width 0)
				(type default)
			)
			(fill yes)
			(layer "B.Fab")
		)
		(pad "1" smd rect
			(at 2.655062 -2.2225 90)
			(size 0.381 1.6002)
			(layers "B.Cu" "B.Mask" "B.Paste")
			(net "MAX11617_2_VREF_R")
		)
		(pad "2" smd rect
			(at 2.655062 -1.5875 90)
			(size 0.381 1.6002)
			(layers "B.Cu" "B.Mask" "B.Paste")
			(net "GND")
		)
		(pad "3" smd rect
			(at 2.655062 -0.9525 90)
			(size 0.381 1.6002)
			(layers "B.Cu" "B.Mask" "B.Paste")
			(net "GND")
		)
		(pad "4" smd rect
			(at 2.655062 -0.3175 90)
			(size 0.381 1.6002)
			(layers "B.Cu" "B.Mask" "B.Paste")
			(net "GND")
		)
		(pad "5" smd rect
			(at 2.655062 0.3175 90)
			(size 0.381 1.6002)
			(layers "B.Cu" "B.Mask" "B.Paste")
			(net "P5V_AUX_ADC_MAM")
		)
		(pad "6" smd rect
			(at 2.655062 0.9525 90)
			(size 0.381 1.6002)
			(layers "B.Cu" "B.Mask" "B.Paste")
			(net "P1V8_AUX_ADC_MAM")
		)
		(pad "7" smd rect
			(at 2.655062 1.5875 90)
			(size 0.381 1.6002)
			(layers "B.Cu" "B.Mask" "B.Paste")
			(net "P1V2_AUX_ADC_MAM")
		)
		(pad "8" smd rect
			(at 2.655062 2.2225 90)
			(size 0.381 1.6002)
			(layers "B.Cu" "B.Mask" "B.Paste")
			(net "P1V8_CPU0_RT_1D_ADC_MAM")
		)
		(pad "9" smd rect
			(at -2.655062 2.2225 90)
			(size 0.381 1.6002)
			(layers "B.Cu" "B.Mask" "B.Paste")
			(net "P1V8_CPU1_RT_1D_ADC_MAM")
		)
		(pad "10" smd rect
			(at -2.655062 1.5875 90)
			(size 0.381 1.6002)
			(layers "B.Cu" "B.Mask" "B.Paste")
			(net "PVDD_33_S5_ADC_MAM")
		)
		(pad "11" smd rect
			(at -2.655062 0.9525 90)
			(size 0.381 1.6002)
			(layers "B.Cu" "B.Mask" "B.Paste")
			(net "PVDD18_S5_P0_ADC_MAM")
		)
		(pad "12" smd rect
			(at -2.655062 0.3175 90)
			(size 0.381 1.6002)
			(layers "B.Cu" "B.Mask" "B.Paste")
			(net "PVDD18_S5_P1_ADC_MAM")
		)
		(pad "13" smd rect
			(at -2.655062 -0.3175 90)
			(size 0.381 1.6002)
			(layers "B.Cu" "B.Mask" "B.Paste")
			(net "SMB_SEN_MAM_2_3V3AUX_SCL")
		)
		(pad "14" smd rect
			(at -2.655062 -0.9525 90)
			(size 0.381 1.6002)
			(layers "B.Cu" "B.Mask" "B.Paste")
			(net "SMB_SEN_MAM_2_3V3AUX_SDA")
		)
		(pad "15" smd rect
			(at -2.655062 -1.5875 90)
			(size 0.381 1.6002)
			(layers "B.Cu" "B.Mask" "B.Paste")
			(net "GND")
		)
		(pad "16" smd rect
			(at -2.655062 -2.2225 90)
			(size 0.381 1.6002)
			(layers "B.Cu" "B.Mask" "B.Paste")
			(net "P3V3_MAX11617_2_VDD")
		)
	)
	(footprint ""
		(layer "B.Cu")
		(at 109.550454 -32.587438 180)
		(property "Reference" "C6092"
			(at 0 0 0)
			(layer "B.SilkS")
			(hide yes)
			(effects
				(font
					(size 1.27 1.27)
				)
				(justify mirror)
			)
		)
		(property "Value" ""
			(at 0 0 0)
			(layer "B.Fab")
			(effects
				(font
					(size 1.27 1.27)
				)
				(justify mirror)
			)
		)
		(duplicate_pad_numbers_are_jumpers no)
		(fp_line
			(start 0.7874 0.4064)
			(end 0.7874 -0.4064)
			(stroke
				(width 0.1524)
				(type default)
			)
			(layer "B.SilkS")
		)
		(fp_line
			(start 0.7874 -0.4064)
			(end -0.7874 -0.4064)
			(stroke
				(width 0.1524)
				(type default)
			)
			(layer "B.SilkS")
		)
		(fp_line
			(start -0.7874 0.4064)
			(end 0.7874 0.4064)
			(stroke
				(width 0.1524)
				(type default)
			)
			(layer "B.SilkS")
		)
		(fp_line
			(start -0.7874 -0.4064)
			(end -0.7874 0.4064)
			(stroke
				(width 0.1524)
				(type default)
			)
			(layer "B.SilkS")
		)
		(fp_line
			(start 0.67945 0.3048)
			(end 0.67945 -0.305054)
			(stroke
				(width 0.1)
				(type default)
			)
			(layer "B.Fab")
		)
		(fp_line
			(start 0.67945 -0.305054)
			(end 0.12065 -0.305054)
			(stroke
				(width 0.1)
				(type default)
			)
			(layer "B.Fab")
		)
		(fp_line
			(start 0.12065 0.3048)
			(end 0.67945 0.3048)
			(stroke
				(width 0.1)
				(type default)
			)
			(layer "B.Fab")
		)
		(fp_line
			(start 0.12065 0.2794)
			(end 0.12065 0.3048)
			(stroke
				(width 0.1)
				(type default)
			)
			(layer "B.Fab")
		)
		(fp_line
			(start 0.12065 -0.2794)
			(end -0.12065 -0.2794)
			(stroke
				(width 0.1)
				(type default)
			)
			(layer "B.Fab")
		)
		(fp_line
			(start 0.12065 -0.305054)
			(end 0.12065 -0.2794)
			(stroke
				(width 0.1)
				(type default)
			)
			(layer "B.Fab")
		)
		(fp_line
			(start -0.120396 0.3048)
			(end -0.120396 0.2794)
			(stroke
				(width 0.1)
				(type default)
			)
			(layer "B.Fab")
		)
		(fp_line
			(start -0.120396 0.2794)
			(end 0.12065 0.2794)
			(stroke
				(width 0.1)
				(type default)
			)
			(layer "B.Fab")
		)
		(fp_line
			(start -0.12065 -0.2794)
			(end -0.12065 -0.3048)
			(stroke
				(width 0.1)
				(type default)
			)
			(layer "B.Fab")
		)
		(fp_line
			(start -0.12065 -0.3048)
			(end -0.67945 -0.3048)
			(stroke
				(width 0.1)
				(type default)
			)
			(layer "B.Fab")
		)
		(fp_line
			(start -0.67945 0.3048)
			(end -0.120396 0.3048)
			(stroke
				(width 0.1)
				(type default)
			)
			(layer "B.Fab")
		)
		(fp_line
			(start -0.67945 -0.3048)
			(end -0.67945 0.3048)
			(stroke
				(width 0.1)
				(type default)
			)
			(layer "B.Fab")
		)
		(pad "1" smd circle
			(at 0.40005 0)
			(size 0 0)
			(layers "B.Cu" "B.Mask" "B.Paste")
			(net "P3V3_AUX_CPU0_USB2_AVDD33")
		)
		(pad "2" smd circle
			(at -0.40005 0)
			(size 0 0)
			(layers "B.Cu" "B.Mask" "B.Paste")
			(net "GND")
		)
	)
)
